(kicad_pcb
	(version 20260206)
	(generator "pcbnew")
	(generator_version "10.0")
	(general
		(thickness 1.6)
		(legacy_teardrops no)
	)
	(paper "A4")
	(title_block
		(title "peb — Lightning_PEB_BRD.brd")
		(comment 1 "Lightning (Wiwynn / Facebook NVMe JBOF) / footprints 1731-1737 of 2563")
	)
	(layers
		(0 "F.Cu" signal "TOP")
		(4 "In1.Cu" signal "L2GND")
		(6 "In2.Cu" signal "L3")
		(8 "In3.Cu" signal "L4VCC")
		(10 "In4.Cu" signal "L5VCC")
		(12 "In5.Cu" signal "L6")
		(14 "In6.Cu" signal "L7GND")
		(2 "B.Cu" signal "BOTTOM")
		(9 "F.Adhes" user "F.Adhesive")
		(11 "B.Adhes" user "B.Adhesive")
		(13 "F.Paste" user "Package Geometry/Pastemask Top")
		(15 "B.Paste" user "Package Geometry/Pastemask Bottom")
		(5 "F.SilkS" user "Ref Des/Silkscreen Top")
		(7 "B.SilkS" user "Ref Des/Silkscreen Bottom")
		(1 "F.Mask" user "Board Geometry/Soldermask Top")
		(3 "B.Mask" user "Board Geometry/Soldermask Bottom")
		(17 "Dwgs.User" user "User.Drawings")
		(19 "Cmts.User" user "User.Comments")
		(21 "Eco1.User" user "User.Eco1")
		(23 "Eco2.User" user "User.Eco2")
		(25 "Edge.Cuts" user "Board Geometry/Outline")
		(27 "Margin" user)
		(31 "F.CrtYd" user "Package Geometry/Place Bound Top")
		(29 "B.CrtYd" user "Package Geometry/Place Bound Bottom")
		(35 "F.Fab" user "Ref Des/Assembly Top")
		(33 "B.Fab" user "Ref Des/Assembly Bottom")
	)
	(footprint ""
		(layer "B.Cu")
		(at 266.486894 -2.567178 180)
		(property "Reference" "R188"
			(at 0 0 0)
			(layer "B.SilkS")
			(hide yes)
			(effects
				(font
					(size 1.27 1.27)
				)
				(justify mirror)
			)
		)
		(property "Value" "4K7R2F-GP"
			(at -0.064008 -3.993896 180)
			(unlocked yes)
			(layer "B.Fab")
			(hide yes)
			(effects
				(font
					(size 1.016 1.016)
					(thickness 0.1524)
				)
				(justify mirror)
			)
		)
		(property "Device Type" "R402H16"
			(at -0.064008 -5.517896 180)
			(unlocked yes)
			(layer "B.Fab")
			(hide yes)
			(effects
				(font
					(size 1.016 1.016)
					(thickness 0.1524)
				)
				(justify mirror)
			)
		)
		(duplicate_pad_numbers_are_jumpers no)
		(fp_line
			(start 0.508 -0.9398)
			(end 0.508 0.9398)
			(stroke
				(width 0.1524)
				(type default)
			)
			(layer "B.SilkS")
		)
		(fp_line
			(start -0.508 -0.9398)
			(end 0.508 -0.9398)
			(stroke
				(width 0.1524)
				(type default)
			)
			(layer "B.SilkS")
		)
		(fp_rect
			(start 0.508 0.9398)
			(end -0.508 -0.9398)
			(stroke
				(width 0)
				(type default)
			)
			(fill no)
			(layer "B.CrtYd")
		)
		(fp_rect
			(start 0.508 0.9398)
			(end -0.508 -0.9398)
			(stroke
				(width 0)
				(type default)
			)
			(fill no)
			(layer "B.Fab")
		)
		(pad "1" smd custom
			(at 0 -0.4445)
			(size 0.1397 0.1397)
			(layers "B.Cu" "B.Mask" "B.Paste")
			(net "P3V3_STBY")
			(options
				(clearance outline)
				(anchor circle)
			)
			(primitives
				(gr_poly
					(pts
						(arc
							(start -0.1778 0.2794)
							(mid -0.249642 0.249642)
							(end -0.2794 0.1778)
						)
						(arc
							(start -0.2794 -0.1778)
							(mid -0.249642 -0.249642)
							(end -0.1778 -0.2794)
						)
						(arc
							(start 0.1778 -0.2794)
							(mid 0.249642 -0.249642)
							(end 0.2794 -0.1778)
						)
						(arc
							(start 0.2794 0.1778)
							(mid 0.249642 0.249642)
							(end 0.1778 0.2794)
						)
					)
					(width 0)
					(fill yes)
				)
			)
		)
		(pad "2" smd custom
			(at 0 0.4445)
			(size 0.1397 0.1397)
			(layers "B.Cu" "B.Mask" "B.Paste")
			(net "TEMP_1_A0")
			(options
				(clearance outline)
				(anchor circle)
			)
			(primitives
				(gr_poly
					(pts
						(arc
							(start -0.1778 0.2794)
							(mid -0.249642 0.249642)
							(end -0.2794 0.1778)
						)
						(arc
							(start -0.2794 -0.1778)
							(mid -0.249642 -0.249642)
							(end -0.1778 -0.2794)
						)
						(arc
							(start 0.1778 -0.2794)
							(mid 0.249642 -0.249642)
							(end 0.2794 -0.1778)
						)
						(arc
							(start 0.2794 0.1778)
							(mid 0.249642 0.249642)
							(end 0.1778 0.2794)
						)
					)
					(width 0)
					(fill yes)
				)
			)
		)
	)
	(footprint ""
		(layer "B.Cu")
		(at 45.212 -138.938)
		(property "Reference" "TP228"
			(at 0 0 0)
			(layer "B.SilkS")
			(hide yes)
			(effects
				(font
					(size 1.27 1.27)
				)
				(justify mirror)
			)
		)
		(property "Value" "TPAD28-2-GP"
			(at 0.0127 -1.6637 0)
			(unlocked yes)
			(layer "B.Fab")
			(hide yes)
			(effects
				(font
					(size 1.016 1.016)
					(thickness 0.1524)
				)
				(justify mirror)
			)
		)
		(property "Device Type" "TPAD28"
			(at 0.0127 -3.1877 0)
			(unlocked yes)
			(layer "B.Fab")
			(hide yes)
			(effects
				(font
					(size 1.016 1.016)
					(thickness 0.1524)
				)
				(justify mirror)
			)
		)
		(duplicate_pad_numbers_are_jumpers no)
		(fp_poly
			(pts
				(arc
					(start 0.3556 0)
					(mid -0.3556 0)
					(end 0.3556 0)
				)
			)
			(stroke
				(width 0)
				(type default)
			)
			(fill no)
			(layer "B.CrtYd")
		)
		(fp_poly
			(pts
				(arc
					(start 0.6096 0)
					(mid -0.6096 0)
					(end 0.6096 0)
				)
			)
			(stroke
				(width 0)
				(type default)
			)
			(fill no)
			(layer "B.Fab")
		)
		(pad "1" smd circle
			(at 0 0 180)
			(size 0.7112 0.7112)
			(layers "B.Cu" "B.Mask" "B.Paste")
			(net "TP_GPION5")
		)
	)
	(footprint ""
		(layer "B.Cu")
		(at 247.0658 -54.006496 90)
		(property "Reference" "C37"
			(at 0 0 90)
			(layer "B.SilkS")
			(hide yes)
			(effects
				(font
					(size 1.27 1.27)
				)
				(justify mirror)
			)
		)
		(property "Value" "SCD1U16V1KX-1-GP"
			(at 2.8321 -1.7399 90)
			(unlocked yes)
			(layer "B.Fab")
			(hide yes)
			(effects
				(font
					(size 1.016 1.016)
					(thickness 0.1524)
				)
				(justify mirror)
			)
		)
		(property "Device Type" "C0201H13"
			(at 2.8321 -3.2639 90)
			(unlocked yes)
			(layer "B.Fab")
			(hide yes)
			(effects
				(font
					(size 1.016 1.016)
					(thickness 0.1524)
				)
				(justify mirror)
			)
		)
		(duplicate_pad_numbers_are_jumpers no)
		(fp_rect
			(start 0.2794 0.6477)
			(end -0.2794 -0.6477)
			(stroke
				(width 0)
				(type default)
			)
			(fill no)
			(layer "B.CrtYd")
		)
		(fp_rect
			(start 0.2794 0.6477)
			(end -0.2794 -0.6477)
			(stroke
				(width 0)
				(type default)
			)
			(fill no)
			(layer "B.Fab")
		)
		(pad "1" smd custom
			(at 0 -0.2794 270)
			(size 0.0762 0.0762)
			(layers "B.Cu" "B.Mask" "B.Paste")
			(net "DUT_VDD")
			(options
				(clearance outline)
				(anchor circle)
			)
			(primitives
				(gr_poly
					(pts
						(arc
							(start 0.1524 0.127)
							(mid 0.137521 0.162921)
							(end 0.1016 0.1778)
						)
						(arc
							(start -0.1016 0.1778)
							(mid -0.137521 0.162921)
							(end -0.1524 0.127)
						)
						(arc
							(start -0.1524 -0.127)
							(mid -0.137521 -0.162921)
							(end -0.1016 -0.1778)
						)
						(arc
							(start 0.1016 -0.1778)
							(mid 0.137521 -0.162921)
							(end 0.1524 -0.127)
						)
					)
					(width 0)
					(fill yes)
				)
			)
		)
		(pad "2" smd custom
			(at 0 0.2794 270)
			(size 0.0762 0.0762)
			(layers "B.Cu" "B.Mask" "B.Paste")
			(net "GND")
			(options
				(clearance outline)
				(anchor circle)
			)
			(primitives
				(gr_poly
					(pts
						(arc
							(start 0.1524 0.127)
							(mid 0.137521 0.162921)
							(end 0.1016 0.1778)
						)
						(arc
							(start -0.1016 0.1778)
							(mid -0.137521 0.162921)
							(end -0.1524 0.127)
						)
						(arc
							(start -0.1524 -0.127)
							(mid -0.137521 -0.162921)
							(end -0.1016 -0.1778)
						)
						(arc
							(start 0.1016 -0.1778)
							(mid 0.137521 -0.162921)
							(end 0.1524 -0.127)
						)
					)
					(width 0)
					(fill yes)
				)
			)
		)
	)
	(footprint ""
		(layer "B.Cu")
		(at 81.129124 -195.427092 180)
		(property "Reference" "R4110"
			(at 0 0 0)
			(layer "B.SilkS")
			(hide yes)
			(effects
				(font
					(size 1.27 1.27)
				)
				(justify mirror)
			)
		)
		(property "Value" "4K7R2F-GP"
			(at -0.064008 -3.993896 180)
			(unlocked yes)
			(layer "B.Fab")
			(hide yes)
			(effects
				(font
					(size 1.016 1.016)
					(thickness 0.1524)
				)
				(justify mirror)
			)
		)
		(property "Device Type" "R402H16"
			(at -0.064008 -5.517896 180)
			(unlocked yes)
			(layer "B.Fab")
			(hide yes)
			(effects
				(font
					(size 1.016 1.016)
					(thickness 0.1524)
				)
				(justify mirror)
			)
		)
		(duplicate_pad_numbers_are_jumpers no)
		(fp_line
			(start 0.508 -0.9398)
			(end 0.508 0.9398)
			(stroke
				(width 0.1524)
				(type default)
			)
			(layer "B.SilkS")
		)
		(fp_line
			(start -0.508 -0.9398)
			(end 0.508 -0.9398)
			(stroke
				(width 0.1524)
				(type default)
			)
			(layer "B.SilkS")
		)
		(fp_rect
			(start 0.508 0.9398)
			(end -0.508 -0.9398)
			(stroke
				(width 0)
				(type default)
			)
			(fill no)
			(layer "B.CrtYd")
		)
		(fp_rect
			(start 0.508 0.9398)
			(end -0.508 -0.9398)
			(stroke
				(width 0)
				(type default)
			)
			(fill no)
			(layer "B.Fab")
		)
		(pad "1" smd custom
			(at 0 -0.4445)
			(size 0.1397 0.1397)
			(layers "B.Cu" "B.Mask" "B.Paste")
			(net "SSD_ATNLED#10")
			(options
				(clearance outline)
				(anchor circle)
			)
			(primitives
				(gr_poly
					(pts
						(arc
							(start -0.1778 0.2794)
							(mid -0.249642 0.249642)
							(end -0.2794 0.1778)
						)
						(arc
							(start -0.2794 -0.1778)
							(mid -0.249642 -0.249642)
							(end -0.1778 -0.2794)
						)
						(arc
							(start 0.1778 -0.2794)
							(mid 0.249642 -0.249642)
							(end 0.2794 -0.1778)
						)
						(arc
							(start 0.2794 0.1778)
							(mid 0.249642 0.249642)
							(end 0.1778 0.2794)
						)
					)
					(width 0)
					(fill yes)
				)
			)
		)
		(pad "2" smd custom
			(at 0 0.4445)
			(size 0.1397 0.1397)
			(layers "B.Cu" "B.Mask" "B.Paste")
			(net "P3V3_STBY")
			(options
				(clearance outline)
				(anchor circle)
			)
			(primitives
				(gr_poly
					(pts
						(arc
							(start -0.1778 0.2794)
							(mid -0.249642 0.249642)
							(end -0.2794 0.1778)
						)
						(arc
							(start -0.2794 -0.1778)
							(mid -0.249642 -0.249642)
							(end -0.1778 -0.2794)
						)
						(arc
							(start 0.1778 -0.2794)
							(mid 0.249642 -0.249642)
							(end 0.2794 -0.1778)
						)
						(arc
							(start 0.2794 0.1778)
							(mid 0.249642 0.249642)
							(end 0.1778 0.2794)
						)
					)
					(width 0)
					(fill yes)
				)
			)
		)
	)
	(footprint ""
		(layer "B.Cu")
		(at 261.62 -13.6906 180)
		(property "Reference" "Q40"
			(at 0 0 0)
			(layer "B.SilkS")
			(hide yes)
			(effects
				(font
					(size 1.27 1.27)
				)
				(justify mirror)
			)
		)
		(property "Value" "2N7002K-1-GP"
			(at -0.127 -8.9662 180)
			(unlocked yes)
			(layer "B.Fab")
			(hide yes)
			(effects
				(font
					(size 1.016 1.016)
					(thickness 0.1524)
				)
				(justify mirror)
			)
		)
		(property "Device Type" "SOT23DGS2D4H44"
			(at -0.127 -10.4902 180)
			(unlocked yes)
			(layer "B.Fab")
			(hide yes)
			(effects
				(font
					(size 1.016 1.016)
					(thickness 0.1524)
				)
				(justify mirror)
			)
		)
		(duplicate_pad_numbers_are_jumpers no)
		(fp_line
			(start 1.651 1.778)
			(end -1.651 1.778)
			(stroke
				(width 0.1524)
				(type default)
			)
			(layer "B.SilkS")
		)
		(fp_line
			(start 1.651 -1.778)
			(end 1.651 1.778)
			(stroke
				(width 0.1524)
				(type default)
			)
			(layer "B.SilkS")
		)
		(fp_line
			(start -1.651 1.778)
			(end -1.651 -1.778)
			(stroke
				(width 0.1524)
				(type default)
			)
			(layer "B.SilkS")
		)
		(fp_line
			(start -1.651 -1.778)
			(end 1.651 -1.778)
			(stroke
				(width 0.1524)
				(type default)
			)
			(layer "B.SilkS")
		)
		(fp_poly
			(pts
				(xy 1.778 1.8796) (xy 1.778 -1.8796) (xy -1.778 -1.8796) (xy -1.778 1.8796)
			)
			(stroke
				(width 0)
				(type default)
			)
			(fill no)
			(layer "B.CrtYd")
		)
		(fp_poly
			(pts
				(xy 1.778 1.8796) (xy 1.778 -1.8796) (xy -1.778 -1.8796) (xy -1.778 1.8796)
			)
			(stroke
				(width 0)
				(type default)
			)
			(fill no)
			(layer "B.Fab")
		)
		(pad "D" smd custom
			(at 0 -0.9525)
			(size 0.1905 0.1905)
			(layers "B.Cu" "B.Mask" "B.Paste")
			(net "Q40_D")
			(options
				(clearance outline)
				(anchor circle)
			)
			(primitives
				(gr_poly
					(pts
						(arc
							(start -0.1778 -0.5715)
							(mid -0.321484 -0.511984)
							(end -0.381 -0.3683)
						)
						(arc
							(start -0.381 0.3683)
							(mid -0.321484 0.511984)
							(end -0.1778 0.5715)
						)
						(arc
							(start 0.1778 0.5715)
							(mid 0.321484 0.511984)
							(end 0.381 0.3683)
						)
						(arc
							(start 0.381 -0.3683)
							(mid 0.321484 -0.511984)
							(end 0.1778 -0.5715)
						)
					)
					(width 0)
					(fill yes)
				)
			)
		)
		(pad "G" smd custom
			(at 0.98425 0.9525)
			(size 0.1905 0.1905)
			(layers "B.Cu" "B.Mask" "B.Paste")
			(net "PWRGD_P1V8_STBY")
			(options
				(clearance outline)
				(anchor circle)
			)
			(primitives
				(gr_poly
					(pts
						(arc
							(start -0.1778 -0.5715)
							(mid -0.321484 -0.511984)
							(end -0.381 -0.3683)
						)
						(arc
							(start -0.381 0.3683)
							(mid -0.321484 0.511984)
							(end -0.1778 0.5715)
						)
						(arc
							(start 0.1778 0.5715)
							(mid 0.321484 0.511984)
							(end 0.381 0.3683)
						)
						(arc
							(start 0.381 -0.3683)
							(mid 0.321484 -0.511984)
							(end 0.1778 -0.5715)
						)
					)
					(width 0)
					(fill yes)
				)
			)
		)
		(pad "S" smd custom
			(at -0.98425 0.9525)
			(size 0.1905 0.1905)
			(layers "B.Cu" "B.Mask" "B.Paste")
			(net "GND")
			(options
				(clearance outline)
				(anchor circle)
			)
			(primitives
				(gr_poly
					(pts
						(arc
							(start -0.1778 -0.5715)
							(mid -0.321484 -0.511984)
							(end -0.381 -0.3683)
						)
						(arc
							(start -0.381 0.3683)
							(mid -0.321484 0.511984)
							(end -0.1778 0.5715)
						)
						(arc
							(start 0.1778 0.5715)
							(mid 0.321484 0.511984)
							(end 0.381 0.3683)
						)
						(arc
							(start 0.381 -0.3683)
							(mid 0.321484 -0.511984)
							(end 0.1778 -0.5715)
						)
					)
					(width 0)
					(fill yes)
				)
			)
		)
	)
	(footprint ""
		(layer "B.Cu")
		(at 128.696212 -205.849474)
		(property "Reference" "R3204"
			(at 0 0 0)
			(layer "B.SilkS")
			(hide yes)
			(effects
				(font
					(size 1.27 1.27)
				)
				(justify mirror)
			)
		)
		(property "Value" "0R2J-2-GP"
			(at -0.064008 -3.993896 0)
			(unlocked yes)
			(layer "B.Fab")
			(hide yes)
			(effects
				(font
					(size 1.016 1.016)
					(thickness 0.1524)
				)
				(justify mirror)
			)
		)
		(property "Device Type" "R402H16"
			(at -0.064008 -5.517896 0)
			(unlocked yes)
			(layer "B.Fab")
			(hide yes)
			(effects
				(font
					(size 1.016 1.016)
					(thickness 0.1524)
				)
				(justify mirror)
			)
		)
		(duplicate_pad_numbers_are_jumpers no)
		(fp_line
			(start -0.508 -0.9398)
			(end 0.508 -0.9398)
			(stroke
				(width 0.1524)
				(type default)
			)
			(layer "B.SilkS")
		)
		(fp_line
			(start 0.508 -0.9398)
			(end 0.508 0.9398)
			(stroke
				(width 0.1524)
				(type default)
			)
			(layer "B.SilkS")
		)
		(fp_rect
			(start 0.508 0.9398)
			(end -0.508 -0.9398)
			(stroke
				(width 0)
				(type default)
			)
			(fill no)
			(layer "B.CrtYd")
		)
		(fp_rect
			(start 0.508 0.9398)
			(end -0.508 -0.9398)
			(stroke
				(width 0)
				(type default)
			)
			(fill no)
			(layer "B.Fab")
		)
		(pad "1" smd custom
			(at 0 -0.4445 180)
			(size 0.1397 0.1397)
			(layers "B.Cu" "B.Mask" "B.Paste")
			(net "SSD_PERST#1")
			(options
				(clearance outline)
				(anchor circle)
			)
			(primitives
				(gr_poly
					(pts
						(arc
							(start -0.1778 0.2794)
							(mid -0.249642 0.249642)
							(end -0.2794 0.1778)
						)
						(arc
							(start -0.2794 -0.1778)
							(mid -0.249642 -0.249642)
							(end -0.1778 -0.2794)
						)
						(arc
							(start 0.1778 -0.2794)
							(mid 0.249642 -0.249642)
							(end 0.2794 -0.1778)
						)
						(arc
							(start 0.2794 0.1778)
							(mid 0.249642 0.249642)
							(end 0.1778 0.2794)
						)
					)
					(width 0)
					(fill yes)
				)
			)
		)
		(pad "2" smd custom
			(at 0 0.4445 180)
			(size 0.1397 0.1397)
			(layers "B.Cu" "B.Mask" "B.Paste")
			(net "SSD_PERST#0_B1")
			(options
				(clearance outline)
				(anchor circle)
			)
			(primitives
				(gr_poly
					(pts
						(arc
							(start -0.1778 0.2794)
							(mid -0.249642 0.249642)
							(end -0.2794 0.1778)
						)
						(arc
							(start -0.2794 -0.1778)
							(mid -0.249642 -0.249642)
							(end -0.1778 -0.2794)
						)
						(arc
							(start 0.1778 -0.2794)
							(mid 0.249642 -0.249642)
							(end 0.2794 -0.1778)
						)
						(arc
							(start 0.2794 0.1778)
							(mid 0.249642 0.249642)
							(end 0.1778 0.2794)
						)
					)
					(width 0)
					(fill yes)
				)
			)
		)
	)
	(footprint ""
		(layer "B.Cu")
		(at 255.831848 -9.123426 -90)
		(property "Reference" "C151"
			(at 0 0 90)
			(layer "B.SilkS")
			(hide yes)
			(effects
				(font
					(size 1.27 1.27)
				)
				(justify mirror)
			)
		)
		(property "Value" "SCD1U16V2KX-3GP"
			(at -1.1811 -2.7051 270)
			(unlocked yes)
			(layer "B.Fab")
			(hide yes)
			(effects
				(font
					(size 1.016 1.016)
					(thickness 0.1524)
				)
				(justify mirror)
			)
		)
		(property "Device Type" "C402H22"
			(at -1.1811 -4.2291 270)
			(unlocked yes)
			(layer "B.Fab")
			(hide yes)
			(effects
				(font
					(size 1.016 1.016)
					(thickness 0.1524)
				)
				(justify mirror)
			)
		)
		(duplicate_pad_numbers_are_jumpers no)
		(fp_rect
			(start 0.4318 0.9525)
			(end -0.4318 -0.9525)
			(stroke
				(width 0)
				(type default)
			)
			(fill no)
			(layer "B.CrtYd")
		)
		(fp_rect
			(start 0.4318 0.9525)
			(end -0.4318 -0.9525)
			(stroke
				(width 0)
				(type default)
			)
			(fill no)
			(layer "B.Fab")
		)
		(pad "1" smd custom
			(at 0 -0.4445 90)
			(size 0.1524 0.1524)
			(layers "B.Cu" "B.Mask" "B.Paste")
			(net "P3V3_STBY")
			(options
				(clearance outline)
				(anchor circle)
			)
			(primitives
				(gr_poly
					(pts
						(arc
							(start 0.3048 0.2032)
							(mid 0.275042 0.275042)
							(end 0.2032 0.3048)
						)
						(arc
							(start -0.2032 0.3048)
							(mid -0.275042 0.275042)
							(end -0.3048 0.2032)
						)
						(arc
							(start -0.3048 -0.2032)
							(mid -0.275042 -0.275042)
							(end -0.2032 -0.3048)
						)
						(arc
							(start 0.2032 -0.3048)
							(mid 0.275042 -0.275042)
							(end 0.3048 -0.2032)
						)
					)
					(width 0)
					(fill yes)
				)
			)
		)
		(pad "2" smd custom
			(at 0 0.4445 90)
			(size 0.1524 0.1524)
			(layers "B.Cu" "B.Mask" "B.Paste")
			(net "GND")
			(options
				(clearance outline)
				(anchor circle)
			)
			(primitives
				(gr_poly
					(pts
						(arc
							(start 0.3048 0.2032)
							(mid 0.275042 0.275042)
							(end 0.2032 0.3048)
						)
						(arc
							(start -0.2032 0.3048)
							(mid -0.275042 0.275042)
							(end -0.3048 0.2032)
						)
						(arc
							(start -0.3048 -0.2032)
							(mid -0.275042 -0.275042)
							(end -0.2032 -0.3048)
						)
						(arc
							(start 0.2032 -0.3048)
							(mid 0.275042 -0.275042)
							(end 0.3048 -0.2032)
						)
					)
					(width 0)
					(fill yes)
				)
			)
		)
	)
)
